(kicad_pcb
	(version 20241229)
	(generator "pcbnew")
	(generator_version "9.0")
	(general
		(thickness 1.63)
		(legacy_teardrops no)
	)
	(paper "A4")
	(title_block
		(title "CM4 Baseboard")
		(date "2026-01-05")
		(rev "1.1.1")
		(company "Antmicro Ltd")
		(comment 1 "www.antmicro.com")
		(comment 9 "footprints 169-174 of 506")
	)
	(layers
		(0 "F.Cu" signal)
		(4 "In1.Cu" power)
		(6 "In2.Cu" power)
		(8 "In3.Cu" signal)
		(10 "In4.Cu" signal)
		(2 "B.Cu" signal)
		(9 "F.Adhes" user "F.Adhesive")
		(11 "B.Adhes" user "B.Adhesive")
		(13 "F.Paste" user)
		(15 "B.Paste" user)
		(5 "F.SilkS" user "F.Silkscreen")
		(7 "B.SilkS" user "B.Silkscreen")
		(1 "F.Mask" user)
		(3 "B.Mask" user)
		(17 "Dwgs.User" user "User.Drawings")
		(19 "Cmts.User" user "User.Comments")
		(21 "Eco1.User" user "User.Eco1")
		(23 "Eco2.User" user "User.Eco2")
		(25 "Edge.Cuts" user)
		(27 "Margin" user)
		(31 "F.CrtYd" user "F.Courtyard")
		(29 "B.CrtYd" user "B.Courtyard")
		(35 "F.Fab" user)
		(33 "B.Fab" user)
	)
	(footprint "antmicro-footprints:R_0402_1005Metric"
		(layer "F.Cu")
		(at 73.442962 157.2915)
		(descr "Resistor SMD 0402")
		(tags "resistor SMD 0402")
		(property "Reference" "R310"
			(at -8.635 -0.215 0)
			(layer "F.SilkS")
			(effects
				(font
					(size 0.7 0.7)
					(thickness 0.15)
				)
				(justify left bottom)
			)
		)
		(property "Value" "R_10k_0402"
			(at -1.011843 1.772047 0)
			(layer "F.Fab")
			(effects
				(font
					(size 0.7 0.7)
					(thickness 0.15)
				)
				(justify left bottom)
			)
		)
		(property "Datasheet" "https://www.bourns.com/docs/product-datasheets/cr.pdf"
			(at 0 0 0)
			(layer "F.Fab")
			(hide yes)
			(effects
				(font
					(size 1.27 1.27)
					(thickness 0.15)
				)
			)
		)
		(property "Manufacturer" "Bourns"
			(at 0 0 0)
			(unlocked yes)
			(layer "F.Fab")
			(hide yes)
			(effects
				(font
					(size 1 1)
					(thickness 0.15)
				)
			)
		)
		(property "MPN" "CR0402-FX-1002GLF"
			(at 0 0 0)
			(unlocked yes)
			(layer "F.Fab")
			(hide yes)
			(effects
				(font
					(size 1 1)
					(thickness 0.15)
				)
			)
		)
		(property "Val" "10k"
			(at 0 0 0)
			(unlocked yes)
			(layer "F.Fab")
			(hide yes)
			(effects
				(font
					(size 1 1)
					(thickness 0.15)
				)
			)
		)
		(property "License" "Apache-2.0"
			(at 0 0 0)
			(unlocked yes)
			(layer "F.Fab")
			(hide yes)
			(effects
				(font
					(size 1 1)
					(thickness 0.15)
				)
			)
		)
		(property "Author" "Antmicro"
			(at 0 0 0)
			(unlocked yes)
			(layer "F.Fab")
			(hide yes)
			(effects
				(font
					(size 1 1)
					(thickness 0.15)
				)
			)
		)
		(property "Tolerance" "1%"
			(at 0 0 0)
			(unlocked yes)
			(layer "F.Fab")
			(hide yes)
			(effects
				(font
					(size 1 1)
					(thickness 0.15)
				)
			)
		)
		(sheetname "/Supply/")
		(sheetfile "supply.kicad_sch")
		(attr smd)
		(fp_rect
			(start -0.925 -0.47)
			(end 0.925 0.47)
			(stroke
				(width 0.05)
				(type default)
			)
			(fill no)
			(layer "F.CrtYd")
		)
		(fp_rect
			(start -0.5 -0.25)
			(end 0.5 0.25)
			(stroke
				(width 0.15)
				(type solid)
			)
			(fill no)
			(layer "F.Fab")
		)
		(fp_text user "${REFERENCE}"
			(at -0.95 3.168 0)
			(layer "F.Fab")
			(effects
				(font
					(size 0.7 0.7)
					(thickness 0.15)
				)
				(justify left bottom)
			)
		)
		(fp_text user "Author: Antmicro"
			(at -0.95 4.169 0)
			(layer "F.Fab")
			(effects
				(font
					(size 0.7 0.7)
					(thickness 0.15)
				)
				(justify left bottom)
			)
		)
		(fp_text user "License: Apache-2.0"
			(at -0.95 5.169 0)
			(layer "F.Fab")
			(effects
				(font
					(size 0.7 0.7)
					(thickness 0.15)
				)
				(justify left bottom)
			)
		)
		(pad "1" smd roundrect
			(at -0.48 0)
			(size 0.59 0.64)
			(layers "F.Cu" "F.Mask" "F.Paste")
			(roundrect_rratio 0.25)
			(net 473 "Net-(D302-A)")
			(pintype "passive")
		)
		(pad "2" smd roundrect
			(at 0.48 0)
			(size 0.59 0.64)
			(layers "F.Cu" "F.Mask" "F.Paste")
			(roundrect_rratio 0.25)
			(net 43 "VCC")
			(pintype "passive")
		)
	)
	(footprint "antmicro-footprints:TP_SMD_0.75mm"
		(layer "F.Cu")
		(at 141.107962 129.7765 180)
		(property "Reference" "TP207"
			(at 0.32 -0.74 180)
			(layer "F.SilkS")
			(effects
				(font
					(size 0.7 0.7)
					(thickness 0.15)
				)
				(justify right bottom)
			)
		)
		(property "Value" "TP_0.75mm_SMD"
			(at 0 1.2 0)
			(layer "F.Fab")
			(effects
				(font
					(size 0.7 0.7)
					(thickness 0.15)
				)
				(justify right bottom)
			)
		)
		(property "Author" "Antmicro"
			(at 0 0 180)
			(unlocked yes)
			(layer "F.Fab")
			(hide yes)
			(effects
				(font
					(size 1 1)
					(thickness 0.15)
				)
			)
		)
		(property "License" "Apache-2.0"
			(at 0 0 180)
			(unlocked yes)
			(layer "F.Fab")
			(hide yes)
			(effects
				(font
					(size 1 1)
					(thickness 0.15)
				)
			)
		)
		(property "MPN" ""
			(at 0 0 180)
			(unlocked yes)
			(layer "F.Fab")
			(hide yes)
			(effects
				(font
					(size 1 1)
					(thickness 0.15)
				)
			)
		)
		(property "Manufacturer" ""
			(at 0 0 180)
			(unlocked yes)
			(layer "F.Fab")
			(hide yes)
			(effects
				(font
					(size 1 1)
					(thickness 0.15)
				)
			)
		)
		(sheetname "/Compute module/")
		(sheetfile "compute-module.kicad_sch")
		(attr exclude_from_pos_files exclude_from_bom)
		(fp_circle
			(center 0 0)
			(end 0.475 0)
			(stroke
				(width 0.05)
				(type default)
			)
			(fill no)
			(layer "F.CrtYd")
		)
		(fp_text user "Author: Antmicro"
			(at -0.4 3.901 180)
			(layer "F.Fab")
			(effects
				(font
					(size 0.7 0.7)
					(thickness 0.15)
				)
				(justify left bottom)
			)
		)
		(fp_text user "License: Apache-2.0"
			(at -0.4 5.101 180)
			(layer "F.Fab")
			(effects
				(font
					(size 0.7 0.7)
					(thickness 0.15)
				)
				(justify left bottom)
			)
		)
		(fp_text user "${REFERENCE}"
			(at -0.4 2.7 180)
			(layer "F.Fab")
			(effects
				(font
					(size 0.7 0.7)
					(thickness 0.15)
				)
				(justify left bottom)
			)
		)
		(pad "1" smd circle
			(at 0 0 180)
			(size 0.75 0.75)
			(layers "F.Cu" "F.Mask")
			(net 250 "/Compute module/~{RPi_BOOT}")
			(pinfunction "1")
			(pintype "passive")
		)
	)
	(footprint "antmicro-footprints:R_0402_1005Metric"
		(layer "F.Cu")
		(at 83.187962 161.5165 180)
		(descr "Resistor SMD 0402")
		(tags "resistor SMD 0402")
		(property "Reference" "R201"
			(at -3.83 -0.475 0)
			(layer "F.SilkS")
			(effects
				(font
					(size 0.7 0.7)
					(thickness 0.15)
				)
				(justify right bottom)
			)
		)
		(property "Value" "R_0R_0402"
			(at -1.011843 1.772047 0)
			(layer "F.Fab")
			(effects
				(font
					(size 0.7 0.7)
					(thickness 0.15)
				)
				(justify right bottom)
			)
		)
		(property "Datasheet" "https://industrial.panasonic.com/cdbs/www-data/pdf/RDA0000/AOA0000C301.pdf"
			(at 0 0 180)
			(layer "F.Fab")
			(hide yes)
			(effects
				(font
					(size 1.27 1.27)
					(thickness 0.15)
				)
			)
		)
		(property "Manufacturer" "Panasonic"
			(at 0 0 180)
			(unlocked yes)
			(layer "F.Fab")
			(hide yes)
			(effects
				(font
					(size 1 1)
					(thickness 0.15)
				)
			)
		)
		(property "MPN" "ERJ2GE0R00X"
			(at 0 0 180)
			(unlocked yes)
			(layer "F.Fab")
			(hide yes)
			(effects
				(font
					(size 1 1)
					(thickness 0.15)
				)
			)
		)
		(property "Val" "0R"
			(at 0 0 180)
			(unlocked yes)
			(layer "F.Fab")
			(hide yes)
			(effects
				(font
					(size 1 1)
					(thickness 0.15)
				)
			)
		)
		(property "License" "Apache-2.0"
			(at 0 0 180)
			(unlocked yes)
			(layer "F.Fab")
			(hide yes)
			(effects
				(font
					(size 1 1)
					(thickness 0.15)
				)
			)
		)
		(property "Author" "Antmicro"
			(at 0 0 180)
			(unlocked yes)
			(layer "F.Fab")
			(hide yes)
			(effects
				(font
					(size 1 1)
					(thickness 0.15)
				)
			)
		)
		(property "Tolerance" "~"
			(at 0 0 180)
			(unlocked yes)
			(layer "F.Fab")
			(hide yes)
			(effects
				(font
					(size 1 1)
					(thickness 0.15)
				)
			)
		)
		(property "Current" "1A"
			(at 0 0 180)
			(unlocked yes)
			(layer "F.Fab")
			(hide yes)
			(effects
				(font
					(size 1 1)
					(thickness 0.15)
				)
			)
		)
		(sheetname "/Compute module/")
		(sheetfile "compute-module.kicad_sch")
		(attr smd)
		(fp_rect
			(start -0.925 -0.47)
			(end 0.925 0.47)
			(stroke
				(width 0.05)
				(type default)
			)
			(fill no)
			(layer "F.CrtYd")
		)
		(fp_rect
			(start -0.5 -0.25)
			(end 0.5 0.25)
			(stroke
				(width 0.15)
				(type solid)
			)
			(fill no)
			(layer "F.Fab")
		)
		(fp_text user "${REFERENCE}"
			(at -0.95 3.168 180)
			(layer "F.Fab")
			(effects
				(font
					(size 0.7 0.7)
					(thickness 0.15)
				)
				(justify left bottom)
			)
		)
		(fp_text user "Author: Antmicro"
			(at -0.95 4.169 180)
			(layer "F.Fab")
			(effects
				(font
					(size 0.7 0.7)
					(thickness 0.15)
				)
				(justify left bottom)
			)
		)
		(fp_text user "License: Apache-2.0"
			(at -0.95 5.169 180)
			(layer "F.Fab")
			(effects
				(font
					(size 0.7 0.7)
					(thickness 0.15)
				)
				(justify left bottom)
			)
		)
		(pad "1" smd roundrect
			(at -0.48 0 180)
			(size 0.59 0.64)
			(layers "F.Cu" "F.Mask" "F.Paste")
			(roundrect_rratio 0.25)
			(net 18 "V_{IO}")
			(pintype "passive")
		)
		(pad "2" smd roundrect
			(at 0.48 0 180)
			(size 0.59 0.64)
			(layers "F.Cu" "F.Mask" "F.Paste")
			(roundrect_rratio 0.25)
			(net 132 "/Compute module/CM4_3V3")
			(pintype "passive")
		)
	)
	(footprint "antmicro-footprints:SOD-123FL"
		(layer "F.Cu")
		(at 40.547962 121.0465 180)
		(property "Reference" "D301"
			(at 2.69 -2.11 180)
			(layer "F.SilkS")
			(effects
				(font
					(size 0.7 0.7)
					(thickness 0.15)
				)
				(justify left bottom)
			)
		)
		(property "Value" "SMF4L15A"
			(at 0 1.967 180)
			(layer "F.Fab")
			(effects
				(font
					(size 0.7 0.7)
					(thickness 0.15)
				)
				(justify left bottom)
			)
		)
		(property "Datasheet" "https://www.littelfuse.com/media?resourcetype=datasheets&itemid=d2ba8fab-1de3-4176-8530-f36ecb0b8799&filename=smf4l"
			(at 0 0 180)
			(layer "F.Fab")
			(hide yes)
			(effects
				(font
					(size 1.27 1.27)
					(thickness 0.15)
				)
			)
		)
		(property "Manufacturer" "Littelfuse"
			(at 0 0 180)
			(unlocked yes)
			(layer "F.Fab")
			(hide yes)
			(effects
				(font
					(size 1 1)
					(thickness 0.15)
				)
			)
		)
		(property "MPN" "SMF4L15A"
			(at 0 0 180)
			(unlocked yes)
			(layer "F.Fab")
			(hide yes)
			(effects
				(font
					(size 1 1)
					(thickness 0.15)
				)
			)
		)
		(property "Author" "Antmicro"
			(at 0 0 180)
			(unlocked yes)
			(layer "F.Fab")
			(hide yes)
			(effects
				(font
					(size 1 1)
					(thickness 0.15)
				)
			)
		)
		(property "License" "Apache-2.0"
			(at 0 0 180)
			(unlocked yes)
			(layer "F.Fab")
			(hide yes)
			(effects
				(font
					(size 1 1)
					(thickness 0.15)
				)
			)
		)
		(sheetname "/Supply/")
		(sheetfile "supply.kicad_sch")
		(attr smd)
		(fp_line
			(start 0 -1.1)
			(end -2.3 -1.1)
			(stroke
				(width 0.15)
				(type solid)
			)
			(layer "F.SilkS")
		)
		(fp_line
			(start -2.3 1.1)
			(end 0 1.1)
			(stroke
				(width 0.15)
				(type solid)
			)
			(layer "F.SilkS")
		)
		(fp_line
			(start -2.3 -1.1)
			(end -2.3 1.1)
			(stroke
				(width 0.15)
				(type solid)
			)
			(layer "F.SilkS")
		)
		(fp_rect
			(start -2.35 -1.125)
			(end 2.35 1.125)
			(stroke
				(width 0.05)
				(type solid)
			)
			(fill no)
			(layer "F.CrtYd")
		)
		(fp_rect
			(start -0.775 -0.875)
			(end -0.525 0.875)
			(stroke
				(width 0.15)
				(type solid)
			)
			(fill yes)
			(layer "F.Fab")
		)
		(fp_rect
			(start -1.825 -0.875)
			(end 1.824 0.873)
			(stroke
				(width 0.15)
				(type solid)
			)
			(fill no)
			(layer "F.Fab")
		)
		(fp_text user "License: Apache-2.0"
			(at -2.406 6.368 180)
			(layer "F.Fab")
			(effects
				(font
					(size 0.7 0.7)
					(thickness 0.15)
				)
				(justify left bottom)
			)
		)
		(fp_text user "Author: Antmicro"
			(at -2.406 5.168 180)
			(layer "F.Fab")
			(effects
				(font
					(size 0.7 0.7)
					(thickness 0.15)
				)
				(justify left bottom)
			)
		)
		(fp_text user "${REFERENCE}"
			(at -2.406 3.967 180)
			(layer "F.Fab")
			(effects
				(font
					(size 0.7 0.7)
					(thickness 0.15)
				)
				(justify left bottom)
			)
		)
		(pad "1" smd roundrect
			(at -1.43 0 180)
			(size 1.34 1.8)
			(layers "F.Cu" "F.Mask" "F.Paste")
			(roundrect_rratio 0.14)
			(net 472 "Net-(D301-C)")
			(pinfunction "C")
			(pintype "passive")
		)
		(pad "2" smd roundrect
			(at 1.429 0 180)
			(size 1.34 1.8)
			(layers "F.Cu" "F.Mask" "F.Paste")
			(roundrect_rratio 0.14)
			(net 3 "GND")
			(pinfunction "A")
			(pintype "passive")
		)
	)
	(footprint "antmicro-footprints:TP_SMD_0.75mm"
		(layer "F.Cu")
		(at 39.3 165.85)
		(property "Reference" "TP306"
			(at 0.45 3.9 90)
			(layer "F.SilkS")
			(effects
				(font
					(size 0.7 0.7)
					(thickness 0.15)
				)
				(justify left bottom)
			)
		)
		(property "Value" "TP_0.75mm_SMD"
			(at 0 1.2 0)
			(layer "F.Fab")
			(effects
				(font
					(size 0.7 0.7)
					(thickness 0.15)
				)
				(justify left bottom)
			)
		)
		(property "MPN" ""
			(at 0 0 0)
			(unlocked yes)
			(layer "F.Fab")
			(hide yes)
			(effects
				(font
					(size 1 1)
					(thickness 0.15)
				)
			)
		)
		(property "Manufacturer" ""
			(at 0 0 0)
			(unlocked yes)
			(layer "F.Fab")
			(hide yes)
			(effects
				(font
					(size 1 1)
					(thickness 0.15)
				)
			)
		)
		(property "Author" "Antmicro"
			(at 0 0 0)
			(unlocked yes)
			(layer "F.Fab")
			(hide yes)
			(effects
				(font
					(size 1 1)
					(thickness 0.15)
				)
			)
		)
		(property "License" "Apache-2.0"
			(at 0 0 0)
			(unlocked yes)
			(layer "F.Fab")
			(hide yes)
			(effects
				(font
					(size 1 1)
					(thickness 0.15)
				)
			)
		)
		(sheetname "/Supply/")
		(sheetfile "supply.kicad_sch")
		(attr exclude_from_pos_files exclude_from_bom)
		(fp_circle
			(center 0 0)
			(end 0.475 0)
			(stroke
				(width 0.05)
				(type default)
			)
			(fill no)
			(layer "F.CrtYd")
		)
		(fp_text user "License: Apache-2.0"
			(at -0.4 5.101 0)
			(layer "F.Fab")
			(effects
				(font
					(size 0.7 0.7)
					(thickness 0.15)
				)
				(justify left bottom)
			)
		)
		(fp_text user "${REFERENCE}"
			(at -0.4 2.7 0)
			(layer "F.Fab")
			(effects
				(font
					(size 0.7 0.7)
					(thickness 0.15)
				)
				(justify left bottom)
			)
		)
		(fp_text user "Author: Antmicro"
			(at -0.4 3.901 0)
			(layer "F.Fab")
			(effects
				(font
					(size 0.7 0.7)
					(thickness 0.15)
				)
				(justify left bottom)
			)
		)
		(pad "1" smd circle
			(at 0 0)
			(size 0.75 0.75)
			(layers "F.Cu" "F.Mask")
			(net 472 "Net-(D301-C)")
			(pinfunction "1")
			(pintype "passive")
		)
	)
	(footprint "antmicro-footprints:R_0402_1005Metric"
		(layer "F.Cu")
		(at 133.387962 154.5665)
		(descr "Resistor SMD 0402")
		(tags "resistor SMD 0402")
		(property "Reference" "R607"
			(at -2.687962 -0.6165 0)
			(layer "F.SilkS")
			(effects
				(font
					(size 0.7 0.7)
					(thickness 0.15)
				)
				(justify left bottom)
			)
		)
		(property "Value" "R_470R_0402"
			(at -1.011843 1.772047 0)
			(layer "F.Fab")
			(effects
				(font
					(size 0.7 0.7)
					(thickness 0.15)
				)
				(justify left bottom)
			)
		)
		(property "Datasheet" "https://www.bourns.com/docs/product-datasheets/cr.pdf"
			(at 0 0 0)
			(layer "F.Fab")
			(hide yes)
			(effects
				(font
					(size 1.27 1.27)
					(thickness 0.15)
				)
			)
		)
		(property "Manufacturer" "Bourns"
			(at 0 0 0)
			(unlocked yes)
			(layer "F.Fab")
			(hide yes)
			(effects
				(font
					(size 1 1)
					(thickness 0.15)
				)
			)
		)
		(property "MPN" "CR0402-FX-4700GLF"
			(at 0 0 0)
			(unlocked yes)
			(layer "F.Fab")
			(hide yes)
			(effects
				(font
					(size 1 1)
					(thickness 0.15)
				)
			)
		)
		(property "Val" "470R"
			(at 0 0 0)
			(unlocked yes)
			(layer "F.Fab")
			(hide yes)
			(effects
				(font
					(size 1 1)
					(thickness 0.15)
				)
			)
		)
		(property "License" "Apache-2.0"
			(at 0 0 0)
			(unlocked yes)
			(layer "F.Fab")
			(hide yes)
			(effects
				(font
					(size 1 1)
					(thickness 0.15)
				)
			)
		)
		(property "Author" "Antmicro"
			(at 0 0 0)
			(unlocked yes)
			(layer "F.Fab")
			(hide yes)
			(effects
				(font
					(size 1 1)
					(thickness 0.15)
				)
			)
		)
		(property "Tolerance" "1%"
			(at 0 0 0)
			(unlocked yes)
			(layer "F.Fab")
			(hide yes)
			(effects
				(font
					(size 1 1)
					(thickness 0.15)
				)
			)
		)
		(sheetname "/CSI/")
		(sheetfile "csi.kicad_sch")
		(attr smd)
		(fp_rect
			(start -0.925 -0.47)
			(end 0.925 0.47)
			(stroke
				(width 0.05)
				(type default)
			)
			(fill no)
			(layer "F.CrtYd")
		)
		(fp_rect
			(start -0.5 -0.25)
			(end 0.5 0.25)
			(stroke
				(width 0.15)
				(type solid)
			)
			(fill no)
			(layer "F.Fab")
		)
		(fp_text user "Author: Antmicro"
			(at -0.95 4.169 0)
			(layer "F.Fab")
			(effects
				(font
					(size 0.7 0.7)
					(thickness 0.15)
				)
				(justify left bottom)
			)
		)
		(fp_text user "License: Apache-2.0"
			(at -0.95 5.169 0)
			(layer "F.Fab")
			(effects
				(font
					(size 0.7 0.7)
					(thickness 0.15)
				)
				(justify left bottom)
			)
		)
		(fp_text user "${REFERENCE}"
			(at -0.95 3.168 0)
			(layer "F.Fab")
			(effects
				(font
					(size 0.7 0.7)
					(thickness 0.15)
				)
				(justify left bottom)
			)
		)
		(pad "1" smd roundrect
			(at -0.48 0)
			(size 0.59 0.64)
			(layers "F.Cu" "F.Mask" "F.Paste")
			(roundrect_rratio 0.25)
			(net 480 "Net-(D602-A)")
			(pintype "passive")
		)
		(pad "2" smd roundrect
			(at 0.48 0)
			(size 0.59 0.64)
			(layers "F.Cu" "F.Mask" "F.Paste")
			(roundrect_rratio 0.25)
			(net 19 "/CSI/CSI_3V3")
			(pintype "passive")
		)
	)
)
